FILE_TYPE = CONNECTIVITY;
{Allegro Design Entry HDL 17.2-2016 S081 (4005846) 1/11/2022}
"PAGE_NUMBER" = 113;
0"NC";
END.
